(kicad_pcb
	(version 20260206)
	(generator "pcbnew")
	(generator_version "10.0")
	(general
		(thickness 1.6)
		(legacy_teardrops no)
	)
	(paper "A4")
	(title_block
		(title "v2-tray-backplane — ms_tbp_v2.brd")
		(comment 1 "Open CloudServer (Microsoft) / footprints 105-112 of 164")
	)
	(layers
		(0 "F.Cu" signal "TOP")
		(4 "In1.Cu" signal "LYR2")
		(6 "In2.Cu" signal "LYR3")
		(8 "In3.Cu" signal "LYR4")
		(10 "In4.Cu" signal "LYR5")
		(12 "In5.Cu" signal "LYR6")
		(14 "In6.Cu" signal "LYR7")
		(2 "B.Cu" signal "BOTTOM")
		(9 "F.Adhes" user "F.Adhesive")
		(11 "B.Adhes" user "B.Adhesive")
		(13 "F.Paste" user "Package Geometry/Pastemask Top")
		(15 "B.Paste" user "Package Geometry/Pastemask Bottom")
		(5 "F.SilkS" user "Ref Des/Silkscreen Top")
		(7 "B.SilkS" user "Ref Des/Silkscreen Bottom")
		(1 "F.Mask" user "Board Geometry/Soldermask Top")
		(3 "B.Mask" user "Board Geometry/Soldermask Bottom")
		(17 "Dwgs.User" user "User.Drawings")
		(19 "Cmts.User" user "User.Comments")
		(21 "Eco1.User" user "User.Eco1")
		(23 "Eco2.User" user "User.Eco2")
		(25 "Edge.Cuts" user "Board Geometry/Outline")
		(27 "Margin" user)
		(31 "F.CrtYd" user "Package Geometry/Place Bound Top")
		(29 "B.CrtYd" user "Package Geometry/Place Bound Bottom")
		(35 "F.Fab" user "Ref Des/Assembly Top")
		(33 "B.Fab" user "Ref Des/Assembly Bottom")
	)
	(footprint ""
		(layer "F.Cu")
		(at -116.250049 32.460001)
		(property "Reference" "J16"
			(at 6.014049 -6.513901 0)
			(unlocked yes)
			(layer "F.SilkS")
			(effects
				(font
					(size 0.762 0.5334)
					(thickness 0.1016)
				)
			)
		)
		(property "Value" ""
			(at 0 0 0)
			(layer "F.Fab")
			(effects
				(font
					(size 1.27 1.27)
				)
			)
		)
		(duplicate_pad_numbers_are_jumpers no)
		(fp_line
			(start -1.925 -5.549999)
			(end 9.924999 -5.549999)
			(stroke
				(width 0.127)
				(type default)
			)
			(layer "F.SilkS")
		)
		(fp_line
			(start -1.925 23.750001)
			(end -1.925 -5.549999)
			(stroke
				(width 0.127)
				(type default)
			)
			(layer "F.SilkS")
		)
		(fp_line
			(start 9.924999 -5.549999)
			(end 9.924999 23.750001)
			(stroke
				(width 0.127)
				(type default)
			)
			(layer "F.SilkS")
		)
		(fp_line
			(start 9.924999 23.750001)
			(end -1.925 23.750001)
			(stroke
				(width 0.127)
				(type default)
			)
			(layer "F.SilkS")
		)
		(fp_poly
			(pts
				(arc
					(start 7.999999 -5.2)
					(mid 11.676954 -3.676955)
					(end 13.199999 0)
				)
				(arc
					(start 13.199999 11.999999)
					(mid 11.676955 15.676956)
					(end 7.999999 17.200001)
				)
				(arc
					(start 0 17.200001)
					(mid -3.676956 15.676955)
					(end -5.2 11.999999)
				)
				(arc
					(start -5.2 0)
					(mid -3.676955 -3.676955)
					(end 0 -5.2)
				)
			)
			(stroke
				(width 0)
				(type default)
			)
			(fill no)
			(layer "B.CrtYd")
		)
		(fp_poly
			(pts
				(xy 10.924999 24.749999) (xy -2.925001 24.749999) (xy -2.925001 -6.549999) (xy 10.924999 -6.549999)
			)
			(stroke
				(width 0)
				(type default)
			)
			(fill no)
			(layer "F.CrtYd")
		)
		(fp_line
			(start -1.925 -5.549999)
			(end 9.924999 -5.549999)
			(stroke
				(width 0.1)
				(type default)
			)
			(layer "F.Fab")
		)
		(fp_line
			(start -1.925 23.750001)
			(end -1.925 -5.549999)
			(stroke
				(width 0.1)
				(type default)
			)
			(layer "F.Fab")
		)
		(fp_line
			(start 9.924999 -5.549999)
			(end 9.924999 23.750001)
			(stroke
				(width 0.1)
				(type default)
			)
			(layer "F.Fab")
		)
		(fp_line
			(start 9.924999 23.750001)
			(end -1.925 23.750001)
			(stroke
				(width 0.1)
				(type default)
			)
			(layer "F.Fab")
		)
		(fp_text user "*"
			(at -2.671451 0 90)
			(unlocked yes)
			(layer "F.SilkS")
			(effects
				(font
					(size 0.381 0.381)
					(thickness 0.381)
				)
			)
		)
		(fp_text user "4"
			(at -2.500001 7.907099 0)
			(unlocked yes)
			(layer "F.SilkS")
			(effects
				(font
					(size 0.762 0.5334)
					(thickness 0.1016)
				)
			)
		)
		(fp_text user "2"
			(at 10.459049 -0.417901 0)
			(unlocked yes)
			(layer "F.SilkS")
			(effects
				(font
					(size 0.762 0.5334)
					(thickness 0.1016)
				)
			)
		)
		(fp_text user "3"
			(at 10.499999 7.907099 0)
			(unlocked yes)
			(layer "F.SilkS")
			(effects
				(font
					(size 0.762 0.5334)
					(thickness 0.1016)
				)
			)
		)
		(pad "" np_thru_hole circle
			(at 4 5.499999)
			(size 1.27 1.27)
			(drill 2.1844)
			(layers "*.Cu" "*.Mask")
		)
		(pad "1A" thru_hole rect
			(at 0 0)
			(size 1.3716 1.3716)
			(drill 0.762)
			(layers "*.Cu" "*.Mask")
			(remove_unused_layers no)
			(net "GND")
			(padstack
				(mode front_inner_back)
				(layer "Inner"
					(shape circle)
					(size 1.3716 1.3716)
				)
				(layer "B.Cu"
					(shape rect)
					(size 1.3716 1.3716)
				)
			)
		)
		(pad "1B" thru_hole circle
			(at 2.000001 0)
			(size 1.3716 1.3716)
			(drill 0.762)
			(layers "*.Cu" "*.Mask")
			(remove_unused_layers no)
			(net "GND")
		)
		(pad "1C" thru_hole circle
			(at 0 2.000001)
			(size 1.3716 1.3716)
			(drill 0.762)
			(layers "*.Cu" "*.Mask")
			(remove_unused_layers no)
			(net "GND")
		)
		(pad "1D" thru_hole circle
			(at 2.000001 2.000001)
			(size 1.3716 1.3716)
			(drill 0.762)
			(layers "*.Cu" "*.Mask")
			(remove_unused_layers no)
			(net "GND")
		)
		(pad "1E" thru_hole circle
			(at 0 4)
			(size 1.3716 1.3716)
			(drill 0.762)
			(layers "*.Cu" "*.Mask")
			(remove_unused_layers no)
			(net "GND")
		)
		(pad "1F" thru_hole circle
			(at 2.000001 4)
			(size 1.3716 1.3716)
			(drill 0.762)
			(layers "*.Cu" "*.Mask")
			(remove_unused_layers no)
			(net "GND")
		)
		(pad "2A" thru_hole circle
			(at 6.000001 0)
			(size 1.3716 1.3716)
			(drill 0.762)
			(layers "*.Cu" "*.Mask")
			(remove_unused_layers no)
			(net "P12V")
		)
		(pad "2B" thru_hole circle
			(at 7.999999 0)
			(size 1.3716 1.3716)
			(drill 0.762)
			(layers "*.Cu" "*.Mask")
			(remove_unused_layers no)
			(net "P12V")
		)
		(pad "2C" thru_hole circle
			(at 6.000001 2.000001)
			(size 1.3716 1.3716)
			(drill 0.762)
			(layers "*.Cu" "*.Mask")
			(remove_unused_layers no)
			(net "P12V")
		)
		(pad "2D" thru_hole circle
			(at 7.999999 2.000001)
			(size 1.3716 1.3716)
			(drill 0.762)
			(layers "*.Cu" "*.Mask")
			(remove_unused_layers no)
			(net "P12V")
		)
		(pad "2E" thru_hole circle
			(at 6.000001 4)
			(size 1.3716 1.3716)
			(drill 0.762)
			(layers "*.Cu" "*.Mask")
			(remove_unused_layers no)
			(net "P12V")
		)
		(pad "2F" thru_hole circle
			(at 7.999999 4)
			(size 1.3716 1.3716)
			(drill 0.762)
			(layers "*.Cu" "*.Mask")
			(remove_unused_layers no)
			(net "P12V")
		)
		(pad "3A" thru_hole circle
			(at 6.000001 7.999999)
			(size 1.3716 1.3716)
			(drill 0.762)
			(layers "*.Cu" "*.Mask")
			(remove_unused_layers no)
			(net "P12V")
		)
		(pad "3B" thru_hole circle
			(at 7.999999 7.999999)
			(size 1.3716 1.3716)
			(drill 0.762)
			(layers "*.Cu" "*.Mask")
			(remove_unused_layers no)
			(net "P12V")
		)
		(pad "3C" thru_hole circle
			(at 6.000001 10)
			(size 1.3716 1.3716)
			(drill 0.762)
			(layers "*.Cu" "*.Mask")
			(remove_unused_layers no)
			(net "P12V")
		)
		(pad "3D" thru_hole circle
			(at 7.999999 10)
			(size 1.3716 1.3716)
			(drill 0.762)
			(layers "*.Cu" "*.Mask")
			(remove_unused_layers no)
			(net "P12V")
		)
		(pad "3E" thru_hole circle
			(at 6.000001 11.999999)
			(size 1.3716 1.3716)
			(drill 0.762)
			(layers "*.Cu" "*.Mask")
			(remove_unused_layers no)
			(net "P12V")
		)
		(pad "3F" thru_hole circle
			(at 7.999999 11.999999)
			(size 1.3716 1.3716)
			(drill 0.762)
			(layers "*.Cu" "*.Mask")
			(remove_unused_layers no)
			(net "P12V")
		)
		(pad "4A" thru_hole circle
			(at 0 7.999999)
			(size 1.3716 1.3716)
			(drill 0.762)
			(layers "*.Cu" "*.Mask")
			(remove_unused_layers no)
			(net "GND")
		)
		(pad "4B" thru_hole circle
			(at 2.000001 7.999999)
			(size 1.3716 1.3716)
			(drill 0.762)
			(layers "*.Cu" "*.Mask")
			(remove_unused_layers no)
			(net "GND")
		)
		(pad "4C" thru_hole circle
			(at 0 10)
			(size 1.3716 1.3716)
			(drill 0.762)
			(layers "*.Cu" "*.Mask")
			(remove_unused_layers no)
			(net "GND")
		)
		(pad "4D" thru_hole circle
			(at 2.000001 10)
			(size 1.3716 1.3716)
			(drill 0.762)
			(layers "*.Cu" "*.Mask")
			(remove_unused_layers no)
			(net "GND")
		)
		(pad "4E" thru_hole circle
			(at 0 11.999999)
			(size 1.3716 1.3716)
			(drill 0.762)
			(layers "*.Cu" "*.Mask")
			(remove_unused_layers no)
			(net "GND")
		)
		(pad "4F" thru_hole circle
			(at 2.000001 11.999999)
			(size 1.3716 1.3716)
			(drill 0.762)
			(layers "*.Cu" "*.Mask")
			(remove_unused_layers no)
			(net "GND")
		)
		(zone
			(layers "F.Cu" "B.Cu" "In1.Cu" "In2.Cu" "In3.Cu" "In4.Cu" "In5.Cu" "In6.Cu")
			(hatch none 0.5)
			(connect_pads
				(clearance 0)
			)
			(min_thickness 0.25)
			(keepout
				(tracks not_allowed)
				(vias allowed)
				(pads allowed)
				(copperpour not_allowed)
				(footprints allowed)
			)
			(placement
				(enabled no)
				(sheetname "")
			)
			(fill
				(thermal_gap 0.5)
				(thermal_bridge_width 0.5)
				(island_removal_mode 0)
			)
			(polygon
				(pts
					(arc
						(start -110.77685 37.96)
						(mid -113.72325 37.96)
						(end -110.77685 37.96)
					)
				)
			)
		)
	)
	(footprint ""
		(layer "F.Cu")
		(at -296.145801 1.384402)
		(property "Reference" "R18"
			(at 3.029801 0.050698 0)
			(unlocked yes)
			(layer "F.SilkS")
			(effects
				(font
					(size 0.762 0.5334)
					(thickness 0.1016)
				)
			)
		)
		(property "Value" ""
			(at 0 0 0)
			(layer "F.Fab")
			(effects
				(font
					(size 1.27 1.27)
				)
			)
		)
		(duplicate_pad_numbers_are_jumpers no)
		(fp_line
			(start 0 -0.381)
			(end 0 0.381)
			(stroke
				(width 0.127)
				(type default)
			)
			(layer "F.SilkS")
		)
		(fp_poly
			(pts
				(xy 1.255601 0.656399) (xy -1.255601 0.656399) (xy -1.255601 -0.6564) (xy 1.255601 -0.6564)
			)
			(stroke
				(width 0)
				(type default)
			)
			(fill no)
			(layer "F.CrtYd")
		)
		(fp_line
			(start -0.800001 -0.4)
			(end -0.800001 0.399999)
			(stroke
				(width 0.1)
				(type default)
			)
			(layer "F.Fab")
		)
		(fp_line
			(start -0.800001 0.399999)
			(end 0.800001 0.399999)
			(stroke
				(width 0.1)
				(type default)
			)
			(layer "F.Fab")
		)
		(fp_line
			(start 0.800001 -0.4)
			(end -0.800001 -0.4)
			(stroke
				(width 0.1)
				(type default)
			)
			(layer "F.Fab")
		)
		(fp_line
			(start 0.800001 0.399999)
			(end 0.800001 -0.4)
			(stroke
				(width 0.1)
				(type default)
			)
			(layer "F.Fab")
		)
		(pad "1" smd rect
			(at -0.650001 0)
			(size 0.7112 0.8128)
			(layers "F.Cu" "F.Mask" "F.Paste")
			(net "P3V3_B1_QSFP")
		)
		(pad "2" smd rect
			(at 0.650001 0 180)
			(size 0.7112 0.8128)
			(layers "F.Cu" "F.Mask" "F.Paste")
			(net "ETH10G_B1_TX_FAULT")
		)
	)
	(footprint ""
		(layer "F.Cu")
		(at -335.846001 21.298002 90)
		(property "Reference" "C4"
			(at -0.418998 -1.300899 90)
			(unlocked yes)
			(layer "F.SilkS")
			(effects
				(font
					(size 0.762 0.5334)
					(thickness 0.1016)
				)
			)
		)
		(property "Value" ""
			(at 0 0 90)
			(layer "F.Fab")
			(effects
				(font
					(size 1.27 1.27)
				)
			)
		)
		(duplicate_pad_numbers_are_jumpers no)
		(fp_poly
			(pts
				(xy -0.999299 0.504) (xy -0.999299 -0.503999) (xy 0.9993 -0.503999) (xy 0.9993 0.504)
			)
			(stroke
				(width 0)
				(type default)
			)
			(fill no)
			(layer "F.CrtYd")
		)
		(fp_line
			(start 0.499999 -0.249999)
			(end 0.499999 0.25)
			(stroke
				(width 0.1)
				(type default)
			)
			(layer "F.Fab")
		)
		(fp_line
			(start -0.499999 -0.249999)
			(end 0.499999 -0.249999)
			(stroke
				(width 0.1)
				(type default)
			)
			(layer "F.Fab")
		)
		(fp_line
			(start 0.499999 0.25)
			(end -0.499999 0.25)
			(stroke
				(width 0.1)
				(type default)
			)
			(layer "F.Fab")
		)
		(fp_line
			(start -0.499999 0.25)
			(end -0.499999 -0.249999)
			(stroke
				(width 0.1)
				(type default)
			)
			(layer "F.Fab")
		)
		(pad "1" smd rect
			(at -0.4572 0 180)
			(size 0.508 0.5842)
			(layers "F.Cu" "F.Mask" "F.Paste")
			(net "P12V")
		)
		(pad "2" smd rect
			(at 0.4572 0 180)
			(size 0.508 0.5842)
			(layers "F.Cu" "F.Mask" "F.Paste")
			(net "GND")
		)
	)
	(footprint ""
		(layer "F.Cu")
		(at -58.610401 45.631202)
		(property "Reference" "FB4"
			(at -0.698599 1.142898 0)
			(unlocked yes)
			(layer "F.SilkS")
			(effects
				(font
					(size 0.762 0.5334)
					(thickness 0.1016)
				)
				(justify left)
			)
		)
		(property "Value" ""
			(at 0 0 0)
			(layer "F.Fab")
			(effects
				(font
					(size 1.27 1.27)
				)
			)
		)
		(duplicate_pad_numbers_are_jumpers no)
		(fp_poly
			(pts
				(xy -1.016 0.508) (xy -1.016 -0.508) (xy 1.016 -0.508) (xy 1.016 0.508)
			)
			(stroke
				(width 0)
				(type default)
			)
			(fill no)
			(layer "F.CrtYd")
		)
		(fp_line
			(start -0.508 -0.254)
			(end 0.508 -0.254)
			(stroke
				(width 0.1)
				(type default)
			)
			(layer "F.Fab")
		)
		(fp_line
			(start -0.508 0.254)
			(end -0.508 -0.254)
			(stroke
				(width 0.1)
				(type default)
			)
			(layer "F.Fab")
		)
		(fp_line
			(start 0.508 -0.254)
			(end 0.508 0.254)
			(stroke
				(width 0.1)
				(type default)
			)
			(layer "F.Fab")
		)
		(fp_line
			(start 0.508 0.254)
			(end -0.508 0.254)
			(stroke
				(width 0.1)
				(type default)
			)
			(layer "F.Fab")
		)
		(pad "1" smd rect
			(at -0.4572 0 90)
			(size 0.508 0.5842)
			(layers "F.Cu" "F.Mask" "F.Paste")
			(net "P3V3_10G_B2_VCCT")
		)
		(pad "2" smd rect
			(at 0.4572 0 90)
			(size 0.508 0.5842)
			(layers "F.Cu" "F.Mask" "F.Paste")
			(net "UNNAMED_6_FERRITE_I27_B")
		)
	)
	(footprint ""
		(layer "F.Cu")
		(at -300.971801 5.956402)
		(property "Reference" "R24"
			(at -3.320199 0.050698 0)
			(unlocked yes)
			(layer "F.SilkS")
			(effects
				(font
					(size 0.762 0.5334)
					(thickness 0.1016)
				)
			)
		)
		(property "Value" ""
			(at 0 0 0)
			(layer "F.Fab")
			(effects
				(font
					(size 1.27 1.27)
				)
			)
		)
		(duplicate_pad_numbers_are_jumpers no)
		(fp_line
			(start 0 -0.381)
			(end 0 0.381)
			(stroke
				(width 0.127)
				(type default)
			)
			(layer "F.SilkS")
		)
		(fp_poly
			(pts
				(xy 1.255601 0.656399) (xy -1.255601 0.656399) (xy -1.255601 -0.6564) (xy 1.255601 -0.6564)
			)
			(stroke
				(width 0)
				(type default)
			)
			(fill no)
			(layer "F.CrtYd")
		)
		(fp_line
			(start -0.800001 -0.4)
			(end -0.800001 0.399999)
			(stroke
				(width 0.1)
				(type default)
			)
			(layer "F.Fab")
		)
		(fp_line
			(start -0.800001 0.399999)
			(end 0.800001 0.399999)
			(stroke
				(width 0.1)
				(type default)
			)
			(layer "F.Fab")
		)
		(fp_line
			(start 0.800001 -0.4)
			(end -0.800001 -0.4)
			(stroke
				(width 0.1)
				(type default)
			)
			(layer "F.Fab")
		)
		(fp_line
			(start 0.800001 0.399999)
			(end 0.800001 -0.4)
			(stroke
				(width 0.1)
				(type default)
			)
			(layer "F.Fab")
		)
		(pad "1" smd rect
			(at -0.650001 0)
			(size 0.7112 0.8128)
			(layers "F.Cu" "F.Mask" "F.Paste")
			(net "P3V3_B1_QSFP")
		)
		(pad "2" smd rect
			(at 0.650001 0 180)
			(size 0.7112 0.8128)
			(layers "F.Cu" "F.Mask" "F.Paste")
			(net "ETH10G_B1_RS1")
		)
	)
	(footprint ""
		(layer "F.Cu")
		(at -80.118801 6.337402)
		(property "Reference" "R30"
			(at -2.939199 -0.076302 0)
			(unlocked yes)
			(layer "F.SilkS")
			(effects
				(font
					(size 0.762 0.5334)
					(thickness 0.1016)
				)
			)
		)
		(property "Value" ""
			(at 0 0 0)
			(layer "F.Fab")
			(effects
				(font
					(size 1.27 1.27)
				)
			)
		)
		(duplicate_pad_numbers_are_jumpers no)
		(fp_line
			(start 0 -0.381)
			(end 0 0.381)
			(stroke
				(width 0.127)
				(type default)
			)
			(layer "F.SilkS")
		)
		(fp_poly
			(pts
				(xy 1.255601 0.656399) (xy -1.255601 0.656399) (xy -1.255601 -0.6564) (xy 1.255601 -0.6564)
			)
			(stroke
				(width 0)
				(type default)
			)
			(fill no)
			(layer "F.CrtYd")
		)
		(fp_line
			(start -0.800001 -0.4)
			(end -0.800001 0.399999)
			(stroke
				(width 0.1)
				(type default)
			)
			(layer "F.Fab")
		)
		(fp_line
			(start -0.800001 0.399999)
			(end 0.800001 0.399999)
			(stroke
				(width 0.1)
				(type default)
			)
			(layer "F.Fab")
		)
		(fp_line
			(start 0.800001 -0.4)
			(end -0.800001 -0.4)
			(stroke
				(width 0.1)
				(type default)
			)
			(layer "F.Fab")
		)
		(fp_line
			(start 0.800001 0.399999)
			(end 0.800001 -0.4)
			(stroke
				(width 0.1)
				(type default)
			)
			(layer "F.Fab")
		)
		(pad "1" smd rect
			(at -0.650001 0)
			(size 0.7112 0.8128)
			(layers "F.Cu" "F.Mask" "F.Paste")
			(net "P3V3_B2_QSFP")
		)
		(pad "2" smd rect
			(at 0.650001 0 180)
			(size 0.7112 0.8128)
			(layers "F.Cu" "F.Mask" "F.Paste")
			(net "SKU_B2_ID0")
		)
	)
	(footprint ""
		(layer "F.Cu")
		(at -296.164 11.176 180)
		(property "Reference" "R28"
			(at -3.048 0.0889 0)
			(unlocked yes)
			(layer "F.SilkS")
			(effects
				(font
					(size 0.762 0.5334)
					(thickness 0.1016)
				)
			)
		)
		(property "Value" ""
			(at 0 0 180)
			(layer "F.Fab")
			(effects
				(font
					(size 1.27 1.27)
				)
			)
		)
		(duplicate_pad_numbers_are_jumpers no)
		(fp_line
			(start 0 -0.381)
			(end 0 0.381)
			(stroke
				(width 0.127)
				(type default)
			)
			(layer "F.SilkS")
		)
		(fp_poly
			(pts
				(xy 1.255601 0.656399) (xy -1.255601 0.656399) (xy -1.255601 -0.6564) (xy 1.255601 -0.6564)
			)
			(stroke
				(width 0)
				(type default)
			)
			(fill no)
			(layer "F.CrtYd")
		)
		(fp_line
			(start 0.800001 0.399999)
			(end 0.800001 -0.399999)
			(stroke
				(width 0.1)
				(type default)
			)
			(layer "F.Fab")
		)
		(fp_line
			(start 0.800001 -0.399999)
			(end -0.800001 -0.399999)
			(stroke
				(width 0.1)
				(type default)
			)
			(layer "F.Fab")
		)
		(fp_line
			(start -0.800001 0.399999)
			(end 0.800001 0.399999)
			(stroke
				(width 0.1)
				(type default)
			)
			(layer "F.Fab")
		)
		(fp_line
			(start -0.800001 -0.399999)
			(end -0.800001 0.399999)
			(stroke
				(width 0.1)
				(type default)
			)
			(layer "F.Fab")
		)
		(pad "1" smd rect
			(at -0.650001 0 180)
			(size 0.7112 0.8128)
			(layers "F.Cu" "F.Mask" "F.Paste")
			(net "P3V3_B1_QSFP")
		)
		(pad "2" smd rect
			(at 0.650001 0)
			(size 0.7112 0.8128)
			(layers "F.Cu" "F.Mask" "F.Paste")
			(net "ETH10G_B1_SCL")
		)
	)
	(footprint ""
		(layer "F.Cu")
		(at -80.0862 7.8486)
		(property "Reference" "R32"
			(at -3.2258 -0.0635 0)
			(unlocked yes)
			(layer "F.SilkS")
			(effects
				(font
					(size 0.762 0.5334)
					(thickness 0.1016)
				)
			)
		)
		(property "Value" ""
			(at 0 0 0)
			(layer "F.Fab")
			(effects
				(font
					(size 1.27 1.27)
				)
			)
		)
		(duplicate_pad_numbers_are_jumpers no)
		(fp_line
			(start 0 -0.381)
			(end 0 0.381)
			(stroke
				(width 0.127)
				(type default)
			)
			(layer "F.SilkS")
		)
		(fp_poly
			(pts
				(xy 1.255601 0.6564) (xy -1.255601 0.6564) (xy -1.255601 -0.656399) (xy 1.255601 -0.656399)
			)
			(stroke
				(width 0)
				(type default)
			)
			(fill no)
			(layer "F.CrtYd")
		)
		(fp_line
			(start -0.800001 -0.399999)
			(end -0.800001 0.399999)
			(stroke
				(width 0.1)
				(type default)
			)
			(layer "F.Fab")
		)
		(fp_line
			(start -0.800001 0.399999)
			(end 0.800001 0.399999)
			(stroke
				(width 0.1)
				(type default)
			)
			(layer "F.Fab")
		)
		(fp_line
			(start 0.800001 -0.399999)
			(end -0.800001 -0.399999)
			(stroke
				(width 0.1)
				(type default)
			)
			(layer "F.Fab")
		)
		(fp_line
			(start 0.800001 0.399999)
			(end 0.800001 -0.399999)
			(stroke
				(width 0.1)
				(type default)
			)
			(layer "F.Fab")
		)
		(pad "1" smd rect
			(at -0.650001 0)
			(size 0.7112 0.8128)
			(layers "F.Cu" "F.Mask" "F.Paste")
			(net "P3V3_B2_QSFP")
		)
		(pad "2" smd rect
			(at 0.650001 0 180)
			(size 0.7112 0.8128)
			(layers "F.Cu" "F.Mask" "F.Paste")
			(net "SKU_B2_ID1")
		)
	)
)
